FILE_TYPE = CONNECTIVITY;
{Allegro Design Entry HDL 17.2-2016 S081 (4005846) 1/11/2022}
"PAGE_NUMBER" = 159;
0"NC";
1"P3V3_AUX\g";
2"P3V3_AUX\g";
3"P3V3_AUX\g";
4"P3V3_AUX\g";
5"P3V3_AUX\g";
6"P3V3_AUX\g";
7"P3V3_AUX\g";
8"GND\g";
9"GND\g";
10"GND\g";
11"GND\g";
12"GND\g";
13"GND\g";
14"GND\g";
15"GND\g";
16"GND\g";
17"GND\g";
18"GND\g";
19"GND\g";
20"FM_P2E_BUF2_EQB0";
21"P2E_BUF2_VDD";
22"FM_P2E_BUF2_EQA0";
23"FM_P2E_BUF2_EQA1";
24"FM_P2E_BUF2_EQB1";
25"FM_P2E_BUF2_EQB0";
26"PD_P2E_BUF2_ENSMB";
27"FM_P2E_BUF2_VODA_DB";
28"FM_P2E_BUF2_VODB_DB";
29"P2E_MB_BMC_TX_C_R2_DP<0>";
30"P2E_MB_BMC_TX_C_R2_DN<0>";
31"P2E_MB_BMC_RX_R2_DP<0>";
32"P2E_MB_BMC_RX_R2_DN<0>";
33"FM_P2E_BUF2_EQA1";
34"FM_P2E_BUF2_EQA0";
35"FM_P2E_BUF2_EQB1";
36"FM_P2E_BUF2_VODB_DB";
37"FM_P2E_BUF2_VODA_DB";
38"P2E_MB_BMC_TX_BUF_C_DN<0>";
39"P2E_MB_BMC_TX_BUF_C_DP<0>";
40"P2E_MB_BMC_RX_R2_DN<0>";
41"P2E_MB_BMC_RX_R1_DP<0>";
42"P2E_MB_BMC_RX_R1_DN<0>";
43"P2E_MB_BMC_RX_R2_DP<0>";
44"P2E_MB_BMC_TX_BUF_DN<0>";
45"FM_P2E_BUF2_RXDET";
46"FM_P2E_EN2_N";
47"FM_P2E_BUF2_SD_TH";
48"NC_RES";
49"CLK_GEN2_GPU_FPGA_OE_OR_N";
50"P2E_MB_BMC_TX_C_R2_DP<0>";
51"P2E_MB_BMC_TX_C_R1_DN<0>";
52"P2E_MB_BMC_TX_C_R1_DP<0>";
53"P2E_MB_BMC_TX_C_R2_DN<0>";
54"P2E_MB_BMC_RX_BUF_DP<0>";
55"P2E_MB_BMC_RX_BUF_DN<0>";
56"P2E_MB_BMC_RX_BUF_C_DN<0>";
57"P2E_MB_BMC_RX_BUF2_C_DP<0>";
58"P2E_MB_BMC_TX_BUF2_DN<0>";
59"P2E_MB_BMC_RX_BUF_C_DP<0>";
60"P2E_MB_BMC_TX_BUF2_DP<0>";
61"P2E_MB_BMC_RX_DP<0>";
62"P2E_MB_BMC_RX_DN<0>";
63"P2E_MB_BMC_TX_C_DN<0>";
64"P2E_MB_BMC_TX_C_DP<0>";
65"P2E_MB_BMC_RX_BUF2_C_DN<0>";
66"P2E_MB_BMC_TX_BUF2_DN<0>";
67"FM_P2E_BUF2_SD_TH";
68"P2E_MB_BMC_RX_BUF2_C_DN<0>";
69"P2E_MB_BMC_TX_BUF_DP<0>";
70"FM_P2E_BUF2_RXDET";
71"FM_P2E_BUF2_VOD_SEL";
72"P2E_MB_BMC_TX_BUF2_DP<0>";
73"P2E_MB_BMC_RX_BUF2_C_DP<0>";
74"FM_P2E_BUF2_VOD_SEL";
%"UNIVERSAL_GND"
"1","(-1550,-2800)","0","logical_power","I1";
;
CDS_LIB"logical_power"
HDL_POWER"GND"
ROOM"IO_SLOT";
"A"8;
%"Q_RES"
"2","(-1550,-1000)","0","pure_quanta","I10";
;
PART_NUMBER"CS21002FB06"
ROOM"PCIE REDRIVER1_BOM2"
MATERIAL"CHIP"
VALUE"1K"
WATTAGE"1/16W"
TOLERANCE"1%"
PACK_TYPE"0402LF"
$LOCATION"R4694"
CDS_LIB"pure_quanta"
CDS_LOCATION"R4694"
$SEC"1"
CDS_SEC"1";
"A"
$PN"1"35;
"B"
$PN"2"10;
%"Q_CAP"
"1","(850,2175)","0","pure_quanta","I100";
;
PART_NUMBER"CH4104K1B00"
PACK_TYPE"0402"
VALUE"0.1UF"
VOLTAGE"25V"
MATERIAL"X7R"
TOLERANCE"10%"
ROOM"PCIE REDRIVER1_BOM2"
$LOCATION"C2358"
CDS_LIB"pure_quanta"
CDS_LOCATION"C2358"
$SEC"1"
CDS_SEC"1";
"B"
$PN"2"18;
"A"
$PN"1"21;
%"UNIVERSAL_GND"
"1","(2375,775)","0","logical_power","I101";
;
HDL_POWER"GND"
CDS_LIB"logical_power";
"A"19;
%"Q_RES"
"1","(2825,1450)","0","pure_quanta","I102";
;
PART_NUMBER"CS00002JB13"
ROOM"PCIE REDRIVER1_BOM2"
PACK_TYPE"0402LF"
MATERIAL"CHIP"
VALUE"0"
$LOCATION"R4651"
WATTAGE"1/16W"
TOLERANCE"5%"
CDS_LIB"pure_quanta"
CDS_LOCATION"R4651"
$SEC"1"
CDS_SEC"1";
"B"
$PN"2"49;
"A"
$PN"1"46;
%"Q_RES"
"2","(-1550,-450)","0","pure_quanta","I11";
;
PART_NUMBER"CS21002FB06"
PACK_TYPE"0402LF"
MATERIAL"EMPTY"
TOLERANCE"1%"
WATTAGE"1/16W"
VALUE"1K"
$LOCATION"R4644"
CDS_LIB"pure_quanta"
CDS_LOCATION"R4644"
$SEC"1"
CDS_SEC"1";
"A"
$PN"1"2;
"B"
$PN"2"35;
%"UNIVERSAL_POWER"
"1","(-1550,-150)","0","logical_power","I12";
;
HDL_POWER"P3V3_AUX"
CDS_LIB"logical_power";
"A"2;
%"Q_RES"
"2","(-1125,-1925)","0","pure_quanta","I13";
;
PART_NUMBER"CS21002FB06"
TOLERANCE"1%"
VALUE"1K"
PACK_TYPE"0402LF"
MATERIAL"EMPTY"
WATTAGE"1/16W"
$LOCATION"R4643"
CDS_LIB"pure_quanta"
CDS_LOCATION"R4643"
$SEC"1"
CDS_SEC"1";
"A"
$PN"1"5;
"B"
$PN"2"37;
%"UNIVERSAL_GND"
"1","(-1125,-1325)","0","logical_power","I14";
;
CDS_LIB"logical_power"
HDL_POWER"GND"
ROOM"IO_SLOT";
"A"11;
%"Q_RES"
"2","(-1125,-1000)","0","pure_quanta","I15";
;
PART_NUMBER"CS21002FB06"
VALUE"1K"
PACK_TYPE"0402LF"
WATTAGE"1/16W"
MATERIAL"EMPTY"
TOLERANCE"1%"
$LOCATION"R4646"
CDS_LIB"pure_quanta"
CDS_LOCATION"R4646"
$SEC"1"
CDS_SEC"1";
"A"
$PN"1"20;
"B"
$PN"2"11;
%"Q_RES"
"2","(-1125,-450)","0","pure_quanta","I16";
;
PART_NUMBER"CS21002FB06"
WATTAGE"1/16W"
PACK_TYPE"0402LF"
VALUE"1K"
TOLERANCE"1%"
MATERIAL"EMPTY"
$LOCATION"R4645"
CDS_LIB"pure_quanta"
CDS_LOCATION"R4645"
$SEC"1"
CDS_SEC"1";
"A"
$PN"1"2;
"B"
$PN"2"20;
%"Q_RES"
"2","(-1550,-2475)","0","pure_quanta","I2";
;
PART_NUMBER"CS21002FB06"
MATERIAL"CHIP"
PACK_TYPE"0402LF"
VALUE"1K"
TOLERANCE"1%"
WATTAGE"1/16W"
ROOM"PCIE REDRIVER1_BOM2"
$LOCATION"R4653"
CDS_LIB"pure_quanta"
CDS_LOCATION"R4653"
$SEC"1"
CDS_SEC"1";
"A"
$PN"1"36;
"B"
$PN"2"8;
%"Q_CAP"
"2","(-2825,25)","0","pure_quanta","I27";
;
PART_NUMBER"CH4104K1B00"
ROOM"PCIE REDRIVER1_BOM2"
MATERIAL"EMPTY"
$LOCATION"C2353"
CDS_LIB"pure_quanta"
PACK_TYPE"0402"
TOLERANCE"10%"
VALUE"0.1UF"
VOLTAGE"25V"
CDS_LOCATION"C2353"
$SEC"1"
CDS_SEC"1";
"A"
$PN"1"57;
"B"
$PN"2"54;
%"Q_CAP"
"2","(-2825,-25)","0","pure_quanta","I28";
;
PART_NUMBER"CH4104K1B00"
ROOM"PCIE REDRIVER1_BOM2"
MATERIAL"EMPTY"
$LOCATION"C2354"
TOLERANCE"10%"
PACK_TYPE"0402"
CDS_LIB"pure_quanta"
VALUE"0.1UF"
VOLTAGE"25V"
CDS_LOCATION"C2354"
$SEC"1"
CDS_SEC"1";
"A"
$PN"1"68;
"B"
$PN"2"55;
%"Q_CAP"
"2","(-2825,250)","0","pure_quanta","I29";
;
PART_NUMBER"CH4104K1B00"
ROOM"PCIE REDRIVER1_BOM1"
$LOCATION"C1868"
VOLTAGE"25V"
VALUE"0.1UF"
TOLERANCE"10%"
PACK_TYPE"0402"
MATERIAL"X7R"
CDS_LIB"pure_quanta"
CDS_LOCATION"C1868"
$SEC"1"
CDS_SEC"1";
"A"
$PN"1"59;
"B"
$PN"2"54;
%"UNIVERSAL_GND"
"1","(-1125,-2800)","0","logical_power","I3";
;
ROOM"IO_SLOT"
HDL_POWER"GND"
CDS_LIB"logical_power";
"A"9;
%"Q_CAP"
"2","(-2825,200)","0","pure_quanta","I30";
;
PART_NUMBER"CH4104K1B00"
ROOM"PCIE REDRIVER1_BOM1"
$LOCATION"C1869"
VOLTAGE"25V"
VALUE"0.1UF"
CDS_LIB"pure_quanta"
MATERIAL"X7R"
PACK_TYPE"0402"
TOLERANCE"10%"
CDS_LOCATION"C1869"
$SEC"1"
CDS_SEC"1";
"A"
$PN"1"56;
"B"
$PN"2"55;
%"Q_CAP"
"2","(-2825,650)","0","pure_quanta","I31";
;
PART_NUMBER"CH4104K1B00"
ROOM"PCIE REDRIVER1_BOM2"
MATERIAL"EMPTY"
$LOCATION"C2351"
VOLTAGE"25V"
VALUE"0.1UF"
TOLERANCE"10%"
PACK_TYPE"0402"
CDS_LIB"pure_quanta"
CDS_LOCATION"C2351"
$SEC"1"
CDS_SEC"1";
"A"
$PN"1"60;
"B"
$PN"2"39;
%"Q_CAP"
"2","(-2825,600)","0","pure_quanta","I32";
;
PART_NUMBER"CH4104K1B00"
ROOM"PCIE REDRIVER1_BOM2"
MATERIAL"EMPTY"
VOLTAGE"25V"
VALUE"0.1UF"
$LOCATION"C2352"
CDS_LIB"pure_quanta"
PACK_TYPE"0402"
TOLERANCE"10%"
CDS_LOCATION"C2352"
$SEC"1"
CDS_SEC"1";
"A"
$PN"1"58;
"B"
$PN"2"38;
%"Q_CAP"
"2","(-2825,875)","0","pure_quanta","I33";
;
PART_NUMBER"CH4104K1B00"
ROOM"PCIE REDRIVER1_BOM1"
$LOCATION"C1870"
VOLTAGE"25V"
VALUE"0.1UF"
TOLERANCE"10%"
PACK_TYPE"0402"
MATERIAL"X7R"
CDS_LIB"pure_quanta"
CDS_LOCATION"C1870"
$SEC"1"
CDS_SEC"1";
"A"
$PN"1"69;
"B"
$PN"2"39;
%"Q_CAP"
"2","(-2825,825)","0","pure_quanta","I34";
;
PART_NUMBER"CH4104K1B00"
PACK_TYPE"0402"
VALUE"0.1UF"
ROOM"PCIE REDRIVER1_BOM1"
TOLERANCE"10%"
VOLTAGE"25V"
MATERIAL"X7R"
$LOCATION"C1871"
CDS_LIB"pure_quanta"
CDS_LOCATION"C1871"
$SEC"1"
CDS_SEC"1";
"A"
$PN"1"44;
"B"
$PN"2"38;
%"Q_RES"
"1","(-2725,1875)","0","pure_quanta","I35";
;
PART_NUMBER"CS00002JB13"
ROOM"PCIE REDRIVER1_BOM2"
MATERIAL"EMPTY"
VALUE"0"
PACK_TYPE"0402LF"
$LOCATION"R4666"
CDS_LIB"pure_quanta"
WATTAGE"1/16W"
TOLERANCE"5%"
CDS_LOCATION"R4666"
$SEC"1"
CDS_SEC"1";
"B"
$PN"2"40;
"A"
$PN"1"62;
%"Q_RES"
"1","(-2725,1925)","0","pure_quanta","I36";
;
PART_NUMBER"CS00002JB13"
ROOM"PCIE REDRIVER1_BOM2"
VALUE"0"
MATERIAL"EMPTY"
PACK_TYPE"0402LF"
$LOCATION"R4665"
CDS_LIB"pure_quanta"
WATTAGE"1/16W"
TOLERANCE"5%"
CDS_LOCATION"R4665"
$SEC"1"
CDS_SEC"1";
"B"
$PN"2"43;
"A"
$PN"1"61;
%"Q_RES"
"2","(-1125,-2475)","0","pure_quanta","I4";
;
PART_NUMBER"CS21002FB06"
ROOM"PCIE REDRIVER1_BOM2"
MATERIAL"CHIP"
TOLERANCE"1%"
PACK_TYPE"0402LF"
WATTAGE"1/16W"
VALUE"1K"
$LOCATION"R4647"
CDS_LIB"pure_quanta"
CDS_LOCATION"R4647"
$SEC"1"
CDS_SEC"1";
"A"
$PN"1"37;
"B"
$PN"2"9;
%"Q_RES"
"1","(-2725,2200)","0","pure_quanta","I41";
;
PART_NUMBER"CS00002JB13"
MATERIAL"CHIP"
ROOM"PCIE REDRIVER1_BOM1"
VALUE"0"
PACK_TYPE"0402LF"
$LOCATION"R4663"
TOLERANCE"5%"
WATTAGE"1/16W"
CDS_LIB"pure_quanta"
CDS_LOCATION"R4663"
$SEC"1"
CDS_SEC"1";
"B"
$PN"2"41;
"A"
$PN"1"61;
%"Q_RES"
"1","(-2725,2150)","0","pure_quanta","I42";
;
PART_NUMBER"CS00002JB13"
ROOM"PCIE REDRIVER1_BOM1"
VALUE"0"
MATERIAL"CHIP"
PACK_TYPE"0402LF"
$LOCATION"R4664"
CDS_LIB"pure_quanta"
TOLERANCE"5%"
WATTAGE"1/16W"
CDS_LOCATION"R4664"
$SEC"1"
CDS_SEC"1";
"B"
$PN"2"42;
"A"
$PN"1"62;
%"Q_RES"
"1","(-2725,2500)","0","pure_quanta","I43";
;
PART_NUMBER"CS00002JB13"
ROOM"PCIE REDRIVER1_BOM2"
PACK_TYPE"0402LF"
VALUE"0"
MATERIAL"EMPTY"
$LOCATION"R4662"
CDS_LIB"pure_quanta"
WATTAGE"1/16W"
TOLERANCE"5%"
CDS_LOCATION"R4662"
$SEC"1"
CDS_SEC"1";
"B"
$PN"2"53;
"A"
$PN"1"63;
%"Q_RES"
"1","(-2725,2550)","0","pure_quanta","I44";
;
PART_NUMBER"CS00002JB13"
ROOM"PCIE REDRIVER1_BOM2"
PACK_TYPE"0402LF"
VALUE"0"
MATERIAL"EMPTY"
$LOCATION"R4661"
CDS_LIB"pure_quanta"
WATTAGE"1/16W"
TOLERANCE"5%"
CDS_LOCATION"R4661"
$SEC"1"
CDS_SEC"1";
"B"
$PN"2"50;
"A"
$PN"1"64;
%"Q_RES"
"1","(-2725,2775)","0","pure_quanta","I45";
;
PART_NUMBER"CS00002JB13"
ROOM"PCIE REDRIVER1_BOM1"
PACK_TYPE"0402LF"
MATERIAL"CHIP"
VALUE"0"
$LOCATION"R4660"
CDS_LIB"pure_quanta"
TOLERANCE"5%"
WATTAGE"1/16W"
CDS_LOCATION"R4660"
$SEC"1"
CDS_SEC"1";
"B"
$PN"2"51;
"A"
$PN"1"63;
%"Q_RES"
"1","(-2725,2825)","0","pure_quanta","I46";
;
PART_NUMBER"CS00002JB13"
ROOM"PCIE REDRIVER1_BOM1"
VALUE"0"
PACK_TYPE"0402LF"
MATERIAL"CHIP"
$LOCATION"R4659"
TOLERANCE"5%"
WATTAGE"1/16W"
CDS_LIB"pure_quanta"
CDS_LOCATION"R4659"
$SEC"1"
CDS_SEC"1";
"B"
$PN"2"52;
"A"
$PN"1"64;
%"UNIVERSAL_GND"
"1","(-825,850)","0","logical_power","I52";
;
CDS_LIB"logical_power"
HDL_POWER"GND";
"A"12;
%"Q_RES"
"2","(-825,1150)","0","pure_quanta","I53";
;
PART_NUMBER"CS21002FB06"
ROOM"PCIE REDRIVER1_BOM2"
PACK_TYPE"0402LF"
MATERIAL"CHIP"
VALUE"1K"
TOLERANCE"1%"
WATTAGE"1/16W"
$LOCATION"R3362"
CDS_LIB"pure_quanta"
CDS_LOCATION"R3362"
$SEC"1"
CDS_SEC"1";
"A"
$PN"1"26;
"B"
$PN"2"12;
%"UNIVERSAL_GND"
"1","(375,-2875)","0","logical_power","I60";
;
CDS_LIB"logical_power"
HDL_POWER"GND"
ROOM"IO_SLOT";
"A"13;
%"Q_RES"
"2","(375,-2650)","0","pure_quanta","I61";
;
PART_NUMBER"CS21002FB06"
VALUE"1K"
TOLERANCE"1%"
PACK_TYPE"0402LF"
MATERIAL"EMPTY"
WATTAGE"1/16W"
$LOCATION"R3381"
CDS_LIB"pure_quanta"
CDS_LOCATION"R3381"
$SEC"1"
CDS_SEC"1";
"A"
$PN"1"70;
"B"
$PN"2"13;
%"Q_RES"
"2","(375,-2125)","0","pure_quanta","I62";
;
PART_NUMBER"CS21002FB06"
PACK_TYPE"0402LF"
MATERIAL"EMPTY"
TOLERANCE"1%"
WATTAGE"1/16W"
VALUE"1K"
$LOCATION"R4655"
CDS_LIB"pure_quanta"
CDS_LOCATION"R4655"
$SEC"1"
CDS_SEC"1";
"A"
$PN"1"7;
"B"
$PN"2"70;
%"UNIVERSAL_GND"
"1","(1575,-2900)","0","logical_power","I64";
;
ROOM"IO_SLOT"
HDL_POWER"GND"
CDS_LIB"logical_power";
"A"14;
%"Q_RES"
"2","(1575,-2675)","0","pure_quanta","I65";
;
PART_NUMBER"CS21002FB06"
MATERIAL"EMPTY"
VALUE"1K"
PACK_TYPE"0402LF"
TOLERANCE"1%"
WATTAGE"1/16W"
$LOCATION"R4657"
CDS_LIB"pure_quanta"
CDS_LOCATION"R4657"
$SEC"1"
CDS_SEC"1";
"A"
$PN"1"67;
"B"
$PN"2"14;
%"Q_RES"
"2","(1575,-2150)","0","pure_quanta","I66";
;
PART_NUMBER"CS21002FB06"
ROOM"PCIE REDRIVER1_BOM2"
PACK_TYPE"0402LF"
VALUE"1K"
MATERIAL"CHIP"
TOLERANCE"1%"
WATTAGE"1/16W"
$LOCATION"R4656"
CDS_LIB"pure_quanta"
CDS_LOCATION"R4656"
$SEC"1"
CDS_SEC"1";
"A"
$PN"1"1;
"B"
$PN"2"67;
%"Q_RES"
"2","(-50,-1025)","0","pure_quanta","I67";
;
PART_NUMBER"CS21002FB06"
TOLERANCE"1%"
PACK_TYPE"0402LF"
MATERIAL"CHIP"
WATTAGE"1/16W"
VALUE"1K"
ROOM"PCIE REDRIVER1_BOM2"
$LOCATION"R4654"
CDS_LIB"pure_quanta"
CDS_LOCATION"R4654"
$SEC"1"
CDS_SEC"1";
"A"
$PN"1"33;
"B"
$PN"2"15;
%"UNIVERSAL_GND"
"1","(-50,-1350)","0","logical_power","I68";
;
ROOM"IO_SLOT"
HDL_POWER"GND"
CDS_LIB"logical_power";
"A"15;
%"UNIVERSAL_POWER"
"1","(375,-1825)","0","logical_power","I69";
;
HDL_POWER"P3V3_AUX"
CDS_LIB"logical_power";
"A"7;
%"Q_RES"
"2","(-1550,-1925)","0","pure_quanta","I7";
;
PART_NUMBER"CS21002FB06"
TOLERANCE"1%"
VALUE"1K"
WATTAGE"1/16W"
MATERIAL"EMPTY"
PACK_TYPE"0402LF"
$LOCATION"R4642"
CDS_LIB"pure_quanta"
CDS_LOCATION"R4642"
$SEC"1"
CDS_SEC"1";
"A"
$PN"1"5;
"B"
$PN"2"36;
%"UNIVERSAL_GND"
"1","(375,-1350)","0","logical_power","I70";
;
CDS_LIB"logical_power"
HDL_POWER"GND"
ROOM"IO_SLOT";
"A"16;
%"Q_RES"
"2","(375,-1025)","0","pure_quanta","I71";
;
PART_NUMBER"CS21002FB06"
PACK_TYPE"0402LF"
VALUE"1K"
MATERIAL"EMPTY"
WATTAGE"1/16W"
TOLERANCE"1%"
$LOCATION"R4650"
CDS_LIB"pure_quanta"
CDS_LOCATION"R4650"
$SEC"1"
CDS_SEC"1";
"A"
$PN"1"34;
"B"
$PN"2"16;
%"Q_RES"
"2","(-50,-475)","0","pure_quanta","I72";
;
PART_NUMBER"CS21002FB06"
WATTAGE"1/16W"
VALUE"1K"
TOLERANCE"1%"
PACK_TYPE"0402LF"
MATERIAL"EMPTY"
$LOCATION"R4648"
CDS_LIB"pure_quanta"
CDS_LOCATION"R4648"
$SEC"1"
CDS_SEC"1";
"A"
$PN"1"4;
"B"
$PN"2"33;
%"UNIVERSAL_POWER"
"1","(-50,-175)","0","logical_power","I73";
;
HDL_POWER"P3V3_AUX"
CDS_LIB"logical_power";
"A"4;
%"Q_RES"
"2","(375,-475)","0","pure_quanta","I74";
;
PART_NUMBER"CS21002FB06"
WATTAGE"1/16W"
VALUE"1K"
TOLERANCE"1%"
PACK_TYPE"0402LF"
MATERIAL"EMPTY"
$LOCATION"R4649"
CDS_LIB"pure_quanta"
CDS_LOCATION"R4649"
$SEC"1"
CDS_SEC"1";
"A"
$PN"1"4;
"B"
$PN"2"34;
%"UNIVERSAL_POWER"
"1","(1575,-1850)","0","logical_power","I75";
;
HDL_POWER"P3V3_AUX"
CDS_LIB"logical_power";
"A"1;
%"UNIVERSAL_GND"
"1","(2750,-2875)","0","logical_power","I79";
;
ROOM"IO_SLOT"
HDL_POWER"GND"
CDS_LIB"logical_power";
"A"17;
%"UNIVERSAL_POWER"
"1","(-1550,-1625)","0","logical_power","I8";
;
HDL_POWER"P3V3_AUX"
CDS_LIB"logical_power";
"A"5;
%"Q_RES"
"2","(2750,-2650)","0","pure_quanta","I80";
;
PART_NUMBER"CS21002FB06"
MATERIAL"EMPTY"
VALUE"1K"
PACK_TYPE"0402LF"
TOLERANCE"1%"
WATTAGE"1/16W"
$LOCATION"R4658"
CDS_LIB"pure_quanta"
CDS_LOCATION"R4658"
$SEC"1"
CDS_SEC"1";
"A"
$PN"1"71;
"B"
$PN"2"17;
%"Q_RES"
"2","(2750,-2125)","0","pure_quanta","I81";
;
PART_NUMBER"CS21002FB06"
ROOM"PCIE REDRIVER1_BOM2"
MATERIAL"CHIP"
PACK_TYPE"0402LF"
VALUE"1K"
TOLERANCE"1%"
WATTAGE"1/16W"
$LOCATION"R3386"
CDS_LIB"pure_quanta"
CDS_LOCATION"R3386"
$SEC"1"
CDS_SEC"1";
"A"
$PN"1"3;
"B"
$PN"2"71;
%"UNIVERSAL_POWER"
"1","(2750,-1825)","0","logical_power","I83";
;
HDL_POWER"P3V3_AUX"
CDS_LIB"logical_power";
"A"3;
%"UNIVERSAL_GND"
"1","(-1550,-1325)","0","logical_power","I9";
;
ROOM"IO_SLOT"
HDL_POWER"GND"
CDS_LIB"logical_power";
"A"10;
%"UNIVERSAL_GND"
"1","(0,1875)","0","logical_power","I94";
;
CDS_LIB"logical_power"
HDL_POWER"GND";
"A"18;
%"DS125BR111RTWR"
"1","(1725,1550)","0","pure_quanta","I95";
;
PART_NUMBER"AL000125003"
VALUE"DS125BR111RTWR"
PART_TYPE"SMLF"
ROOM"PCIE REDRIVER1_BOM2"
MATERIAL"EMPTY"
$LOCATION"U328"
SEC_TYPE""
NEEDS_NO_SIZE"TRUE"
CDS_LMAN_SYM_OUTLINE"-375,700,375,-700"
CDS_LIB"pure_quanta"
CDS_LOCATION"U328"
SEC"1";
"TH_GND"
$PN"25"19;
"INA+"
$PN"24"29;
"INA-"
$PN"23"30;
"VDD_22"
$PN"22"21;
"VDD_21"
$PN"21"21;
"OUTB+"
$PN"20"73;
"OUTB-"
$PN"19"65;
"RXDET||DONE#"
$PN"18"45;
"VOD_SEL||READEN#"
$PN"17"74;
"VDD_SEL"
$PN"16"18;
"VIN"
$PN"15"6;
"SD_TH"
$PN"14"47;
"RES"
$PN"13"48;
"INB-"
$PN"12"32;
"INB+"
$PN"11"31;
"EQA0||AD0"
$PN"10"22;
"EQA1||AD1"
$PN"9"23;
"OUTA-"
$PN"8"66;
"OUTA+"
$PN"7"72;
"PWDN"
$PN"6"46;
"SCL||VODB_DB"
$PN"5"28;
"SDA||VODA_DB"
$PN"4"27;
"ENSMB"
$PN"3"26;
"EQB1||AD2"
$PN"2"24;
"EQB0||AD3"
$PN"1"25;
%"Q_CAP"
"1","(0,2175)","2","pure_quanta","I96";
;
PART_NUMBER"CH5104KEB02"
VALUE"1UF"
VOLTAGE"25V"
PACK_TYPE"C0402"
TOLERANCE"10%"
MATERIAL"X6S"
ROOM"PCIE REDRIVER1_BOM2"
$LOCATION"C2355"
CDS_LIB"pure_quanta"
CDS_LOCATION"C2355"
$SEC"1"
CDS_SEC"1";
"B"
$PN"2"18;
"A"
$PN"1"6;
%"UNIVERSAL_POWER"
"1","(0,2550)","0","logical_power","I97";
;
HDL_POWER"P3V3_AUX"
CDS_LIB"logical_power";
"A"6;
%"Q_CAP"
"1","(325,2175)","2","pure_quanta","I98";
;
PART_NUMBER"CH6103KEA00"
MATERIAL"X6S"
VOLTAGE"16V"
TOLERANCE"10%"
PACK_TYPE"C0805"
VALUE"10UF"
ROOM"PCIE REDRIVER1_BOM2"
$LOCATION"C2356"
BOM_COST"VR_SYSTEM "
CDS_LIB"pure_quanta"
CDS_LOCATION"C2356"
$SEC"1"
CDS_SEC"1";
"B"
$PN"2"18;
"A"
$PN"1"6;
%"Q_CAP"
"1","(625,2175)","0","pure_quanta","I99";
;
PART_NUMBER"CH4104K1B00"
PACK_TYPE"0402"
TOLERANCE"10%"
MATERIAL"X7R"
VALUE"0.1UF"
VOLTAGE"25V"
ROOM"PCIE REDRIVER1_BOM2"
$LOCATION"C2357"
CDS_LIB"pure_quanta"
CDS_LOCATION"C2357"
$SEC"1"
CDS_SEC"1";
"B"
$PN"2"18;
"A"
$PN"1"21;
END.
